(kicad_pcb
	(version 20241229)
	(generator "pcbnew")
	(generator_version "9.0")
	(general
		(thickness 1.599998)
		(legacy_teardrops no)
	)
	(paper "A4")
	(title_block
		(date "2023-02-12")
		(rev "1.1.5")
		(comment 9 "footprints 364-370 of 473")
	)
	(layers
		(0 "F.Cu" signal)
		(4 "In1.Cu" power "In1.GND")
		(6 "In2.Cu" signal)
		(8 "In3.Cu" power "In3.GND")
		(10 "In4.Cu" power "In4.VCC")
		(12 "In5.Cu" signal)
		(14 "In6.Cu" power "In6.VCC")
		(2 "B.Cu" signal)
		(9 "F.Adhes" user "F.Adhesive")
		(11 "B.Adhes" user "B.Adhesive")
		(13 "F.Paste" user)
		(15 "B.Paste" user)
		(5 "F.SilkS" user "F.Silkscreen")
		(7 "B.SilkS" user "B.Silkscreen")
		(1 "F.Mask" user)
		(3 "B.Mask" user)
		(17 "Dwgs.User" user "User.Drawings")
		(19 "Cmts.User" user "User.Comments")
		(21 "Eco1.User" user "User.Eco1")
		(23 "Eco2.User" user "User.Eco2")
		(25 "Edge.Cuts" user)
		(27 "Margin" user)
		(31 "F.CrtYd" user "F.Courtyard")
		(29 "B.CrtYd" user "B.Courtyard")
		(35 "F.Fab" user)
		(33 "B.Fab" user)
	)
	(footprint "antmicro-footprints:C_0201"
		(layer "B.Cu")
		(at 166 89.875)
		(descr "Capacitor SMD 0201")
		(tags "capacitor SMD 0201")
		(property "Reference" "C55"
			(at 0.8 -0.375 180)
			(layer "B.SilkS")
			(effects
				(font
					(size 0.7 0.7)
					(thickness 0.15)
				)
				(justify left bottom mirror)
			)
		)
		(property "Value" "C_100n_0201"
			(at 0 -1.4 180)
			(layer "B.Fab")
			(effects
				(font
					(size 0.7 0.7)
					(thickness 0.15)
				)
				(justify left bottom mirror)
			)
		)
		(property "Description" " "
			(at 0 0 0)
			(layer "F.Fab")
			(hide yes)
			(effects
				(font
					(size 1.27 1.27)
					(thickness 0.15)
				)
			)
		)
		(property "Author" "Antmicro"
			(at 0 0 0)
			(layer "B.Fab")
			(hide yes)
			(effects
				(font
					(size 1 1)
					(thickness 0.15)
				)
				(justify mirror)
			)
		)
		(property "Dielectric" ""
			(at 0 0 0)
			(layer "B.Fab")
			(hide yes)
			(effects
				(font
					(size 1 1)
					(thickness 0.15)
				)
				(justify mirror)
			)
		)
		(property "License" "Apache-2.0"
			(at 0 0 0)
			(layer "B.Fab")
			(hide yes)
			(effects
				(font
					(size 1 1)
					(thickness 0.15)
				)
				(justify mirror)
			)
		)
		(property "MPN" "CC0201KRX6S5BB104"
			(at 0 0 0)
			(layer "B.Fab")
			(hide yes)
			(effects
				(font
					(size 1 1)
					(thickness 0.15)
				)
				(justify mirror)
			)
		)
		(property "Manufacturer" "Yaego"
			(at 0 0 0)
			(layer "B.Fab")
			(hide yes)
			(effects
				(font
					(size 1 1)
					(thickness 0.15)
				)
				(justify mirror)
			)
		)
		(property "Val" "100n"
			(at 0 0 0)
			(layer "B.Fab")
			(hide yes)
			(effects
				(font
					(size 1 1)
					(thickness 0.15)
				)
				(justify mirror)
			)
		)
		(property "Voltage" ""
			(at 0 0 0)
			(layer "B.Fab")
			(hide yes)
			(effects
				(font
					(size 1 1)
					(thickness 0.15)
				)
				(justify mirror)
			)
		)
		(sheetname "FPGA power")
		(sheetfile "fpga-power.kicad_sch")
		(attr smd)
		(fp_rect
			(start -0.72 0.38)
			(end 0.72 -0.38)
			(stroke
				(width 0.05)
				(type solid)
			)
			(fill no)
			(layer "B.CrtYd")
		)
		(fp_rect
			(start 0.3 -0.15)
			(end -0.301 0.149)
			(stroke
				(width 0.15)
				(type solid)
			)
			(fill no)
			(layer "B.Fab")
		)
		(pad "" smd roundrect
			(at -0.349 0.002)
			(size 0.318 0.36)
			(layers "B.Paste")
			(roundrect_rratio 0.25)
		)
		(pad "" smd roundrect
			(at 0.341 0.002)
			(size 0.318 0.36)
			(layers "B.Paste")
			(roundrect_rratio 0.25)
		)
		(pad "1" smd roundrect
			(at -0.321 0.002)
			(size 0.46 0.4)
			(layers "B.Cu" "B.Mask")
			(roundrect_rratio 0.25)
			(net 66 "VDDQ")
			(pintype "passive")
		)
		(pad "2" smd roundrect
			(at 0.32 0.002)
			(size 0.46 0.4)
			(layers "B.Cu" "B.Mask")
			(roundrect_rratio 0.25)
			(net 5 "GND")
			(pintype "passive")
		)
	)
	(footprint "antmicro-footprints:C_0201"
		(layer "B.Cu")
		(at 162.375 93.5 -90)
		(descr "Capacitor SMD 0201")
		(tags "capacitor SMD 0201")
		(property "Reference" "C61"
			(at -1.6 -1.125 90)
			(layer "B.SilkS")
			(effects
				(font
					(size 0.7 0.7)
					(thickness 0.15)
				)
				(justify left bottom mirror)
			)
		)
		(property "Value" "C_100n_0201"
			(at 0 -1.4 90)
			(layer "B.Fab")
			(effects
				(font
					(size 0.7 0.7)
					(thickness 0.15)
				)
				(justify left bottom mirror)
			)
		)
		(property "Description" " "
			(at 0 0 270)
			(layer "F.Fab")
			(hide yes)
			(effects
				(font
					(size 1.27 1.27)
					(thickness 0.15)
				)
			)
		)
		(property "Author" "Antmicro"
			(at 68.875 255.875 0)
			(layer "B.Fab")
			(hide yes)
			(effects
				(font
					(size 1 1)
					(thickness 0.15)
				)
				(justify mirror)
			)
		)
		(property "Dielectric" ""
			(at 68.875 255.875 0)
			(layer "B.Fab")
			(hide yes)
			(effects
				(font
					(size 1 1)
					(thickness 0.15)
				)
				(justify mirror)
			)
		)
		(property "License" "Apache-2.0"
			(at 68.875 255.875 0)
			(layer "B.Fab")
			(hide yes)
			(effects
				(font
					(size 1 1)
					(thickness 0.15)
				)
				(justify mirror)
			)
		)
		(property "MPN" "CC0201KRX6S5BB104"
			(at 68.875 255.875 0)
			(layer "B.Fab")
			(hide yes)
			(effects
				(font
					(size 1 1)
					(thickness 0.15)
				)
				(justify mirror)
			)
		)
		(property "Manufacturer" "Yaego"
			(at 68.875 255.875 0)
			(layer "B.Fab")
			(hide yes)
			(effects
				(font
					(size 1 1)
					(thickness 0.15)
				)
				(justify mirror)
			)
		)
		(property "Val" "100n"
			(at 68.875 255.875 0)
			(layer "B.Fab")
			(hide yes)
			(effects
				(font
					(size 1 1)
					(thickness 0.15)
				)
				(justify mirror)
			)
		)
		(property "Voltage" ""
			(at 68.875 255.875 0)
			(layer "B.Fab")
			(hide yes)
			(effects
				(font
					(size 1 1)
					(thickness 0.15)
				)
				(justify mirror)
			)
		)
		(sheetname "FPGA power")
		(sheetfile "fpga-power.kicad_sch")
		(attr smd)
		(fp_rect
			(start -0.72 0.38)
			(end 0.72 -0.38)
			(stroke
				(width 0.05)
				(type solid)
			)
			(fill no)
			(layer "B.CrtYd")
		)
		(fp_rect
			(start 0.3 -0.15)
			(end -0.301 0.149)
			(stroke
				(width 0.15)
				(type solid)
			)
			(fill no)
			(layer "B.Fab")
		)
		(pad "" smd roundrect
			(at -0.349 0.002 270)
			(size 0.318 0.36)
			(layers "B.Paste")
			(roundrect_rratio 0.25)
		)
		(pad "" smd roundrect
			(at 0.341 0.002 270)
			(size 0.318 0.36)
			(layers "B.Paste")
			(roundrect_rratio 0.25)
		)
		(pad "1" smd roundrect
			(at -0.321 0.002 270)
			(size 0.46 0.4)
			(layers "B.Cu" "B.Mask")
			(roundrect_rratio 0.25)
			(net 66 "VDDQ")
			(pintype "passive")
		)
		(pad "2" smd roundrect
			(at 0.32 0.002 270)
			(size 0.46 0.4)
			(layers "B.Cu" "B.Mask")
			(roundrect_rratio 0.25)
			(net 5 "GND")
			(pintype "passive")
		)
	)
	(footprint "antmicro-footprints:R_0402_1005Metric"
		(layer "B.Cu")
		(at 180.1885 117.015757)
		(descr "Resistor SMD 0402")
		(tags "resistor SMD 0402")
		(property "Reference" "R56"
			(at -0.7885 0.384243 180)
			(layer "B.SilkS")
			(effects
				(font
					(size 0.7 0.7)
					(thickness 0.15)
				)
				(justify left bottom mirror)
			)
		)
		(property "Value" "R_4k7_0402"
			(at 0 -1.4 180)
			(layer "B.Fab")
			(effects
				(font
					(size 0.7 0.7)
					(thickness 0.15)
				)
				(justify left bottom mirror)
			)
		)
		(property "Description" "4k7 resistor in 0402 package with 1% tolerance"
			(at 0 0 0)
			(layer "F.Fab")
			(hide yes)
			(effects
				(font
					(size 1.27 1.27)
					(thickness 0.15)
				)
			)
		)
		(property "Author" "Antmicro"
			(at 0 0 0)
			(layer "B.Fab")
			(hide yes)
			(effects
				(font
					(size 1 1)
					(thickness 0.15)
				)
				(justify mirror)
			)
		)
		(property "License" "Apache-2.0"
			(at 0 0 0)
			(layer "B.Fab")
			(hide yes)
			(effects
				(font
					(size 1 1)
					(thickness 0.15)
				)
				(justify mirror)
			)
		)
		(property "MPN" "CR0402-FX-4701GLF"
			(at 0 0 0)
			(layer "B.Fab")
			(hide yes)
			(effects
				(font
					(size 1 1)
					(thickness 0.15)
				)
				(justify mirror)
			)
		)
		(property "Manufacturer" "Bourns"
			(at 0 0 0)
			(layer "B.Fab")
			(hide yes)
			(effects
				(font
					(size 1 1)
					(thickness 0.15)
				)
				(justify mirror)
			)
		)
		(property "Tolerance" "1%"
			(at 0 0 0)
			(layer "B.Fab")
			(hide yes)
			(effects
				(font
					(size 1 1)
					(thickness 0.15)
				)
				(justify mirror)
			)
		)
		(property "Val" "4k7"
			(at 0 0 0)
			(layer "B.Fab")
			(hide yes)
			(effects
				(font
					(size 1 1)
					(thickness 0.15)
				)
				(justify mirror)
			)
		)
		(sheetname "Config SPI flash")
		(sheetfile "config-spi.kicad_sch")
		(attr smd)
		(fp_rect
			(start -0.93 0.47)
			(end 0.93 -0.47)
			(stroke
				(width 0.05)
				(type solid)
			)
			(fill no)
			(layer "B.CrtYd")
		)
		(fp_rect
			(start -0.5 0.25)
			(end 0.5 -0.25)
			(stroke
				(width 0.15)
				(type solid)
			)
			(fill no)
			(layer "B.Fab")
		)
		(pad "1" smd roundrect
			(at -0.485 0)
			(size 0.59 0.64)
			(layers "B.Cu" "B.Mask" "B.Paste")
			(roundrect_rratio 0.25)
			(net 459 "3V3_SYS")
			(pintype "passive")
		)
		(pad "2" smd roundrect
			(at 0.485 0)
			(size 0.59 0.64)
			(layers "B.Cu" "B.Mask" "B.Paste")
			(roundrect_rratio 0.25)
			(net 18 "QSPI_DQ3")
			(pintype "passive")
		)
	)
	(footprint "antmicro-footprints:R_0402_1005Metric"
		(layer "B.Cu")
		(at 168.822 118.285757 180)
		(descr "Resistor SMD 0402")
		(tags "resistor SMD 0402")
		(property "Reference" "R59"
			(at -2.978 -0.454243 0)
			(layer "B.SilkS")
			(effects
				(font
					(size 0.7 0.7)
					(thickness 0.15)
				)
				(justify left bottom mirror)
			)
		)
		(property "Value" "R_4k7_0402"
			(at 0 -1.4 0)
			(layer "B.Fab")
			(effects
				(font
					(size 0.7 0.7)
					(thickness 0.15)
				)
				(justify left bottom mirror)
			)
		)
		(property "Description" "4k7 resistor in 0402 package with 1% tolerance"
			(at 0 0 180)
			(layer "F.Fab")
			(hide yes)
			(effects
				(font
					(size 1.27 1.27)
					(thickness 0.15)
				)
			)
		)
		(property "Author" "Antmicro"
			(at 337.644 236.571514 0)
			(layer "B.Fab")
			(hide yes)
			(effects
				(font
					(size 1 1)
					(thickness 0.15)
				)
				(justify mirror)
			)
		)
		(property "License" "Apache-2.0"
			(at 337.644 236.571514 0)
			(layer "B.Fab")
			(hide yes)
			(effects
				(font
					(size 1 1)
					(thickness 0.15)
				)
				(justify mirror)
			)
		)
		(property "MPN" "CR0402-FX-4701GLF"
			(at 337.644 236.571514 0)
			(layer "B.Fab")
			(hide yes)
			(effects
				(font
					(size 1 1)
					(thickness 0.15)
				)
				(justify mirror)
			)
		)
		(property "Manufacturer" "Bourns"
			(at 337.644 236.571514 0)
			(layer "B.Fab")
			(hide yes)
			(effects
				(font
					(size 1 1)
					(thickness 0.15)
				)
				(justify mirror)
			)
		)
		(property "Tolerance" "1%"
			(at 337.644 236.571514 0)
			(layer "B.Fab")
			(hide yes)
			(effects
				(font
					(size 1 1)
					(thickness 0.15)
				)
				(justify mirror)
			)
		)
		(property "Val" "4k7"
			(at 337.644 236.571514 0)
			(layer "B.Fab")
			(hide yes)
			(effects
				(font
					(size 1 1)
					(thickness 0.15)
				)
				(justify mirror)
			)
		)
		(sheetname "Config SPI flash")
		(sheetfile "config-spi.kicad_sch")
		(attr smd)
		(fp_rect
			(start -0.93 0.47)
			(end 0.93 -0.47)
			(stroke
				(width 0.05)
				(type solid)
			)
			(fill no)
			(layer "B.CrtYd")
		)
		(fp_rect
			(start -0.5 0.25)
			(end 0.5 -0.25)
			(stroke
				(width 0.15)
				(type solid)
			)
			(fill no)
			(layer "B.Fab")
		)
		(pad "1" smd roundrect
			(at -0.485 0 180)
			(size 0.59 0.64)
			(layers "B.Cu" "B.Mask" "B.Paste")
			(roundrect_rratio 0.25)
			(net 459 "3V3_SYS")
			(pintype "passive")
		)
		(pad "2" smd roundrect
			(at 0.485 0 180)
			(size 0.59 0.64)
			(layers "B.Cu" "B.Mask" "B.Paste")
			(roundrect_rratio 0.25)
			(net 17 "QSPI_DQ2")
			(pintype "passive")
		)
	)
	(footprint "antmicro-footprints:C_0201"
		(layer "B.Cu")
		(at 163.125 97 180)
		(descr "Capacitor SMD 0201")
		(tags "capacitor SMD 0201")
		(property "Reference" "C65"
			(at 0.525 -0.4 0)
			(layer "B.SilkS")
			(effects
				(font
					(size 0.7 0.7)
					(thickness 0.15)
				)
				(justify left bottom mirror)
			)
		)
		(property "Value" "C_100n_0201"
			(at 0 -1.4 0)
			(layer "B.Fab")
			(effects
				(font
					(size 0.7 0.7)
					(thickness 0.15)
				)
				(justify left bottom mirror)
			)
		)
		(property "Description" " "
			(at 0 0 180)
			(layer "F.Fab")
			(hide yes)
			(effects
				(font
					(size 1.27 1.27)
					(thickness 0.15)
				)
			)
		)
		(property "Author" "Antmicro"
			(at 326.25 194 0)
			(layer "B.Fab")
			(hide yes)
			(effects
				(font
					(size 1 1)
					(thickness 0.15)
				)
				(justify mirror)
			)
		)
		(property "Dielectric" ""
			(at 326.25 194 0)
			(layer "B.Fab")
			(hide yes)
			(effects
				(font
					(size 1 1)
					(thickness 0.15)
				)
				(justify mirror)
			)
		)
		(property "License" "Apache-2.0"
			(at 326.25 194 0)
			(layer "B.Fab")
			(hide yes)
			(effects
				(font
					(size 1 1)
					(thickness 0.15)
				)
				(justify mirror)
			)
		)
		(property "MPN" "CC0201KRX6S5BB104"
			(at 326.25 194 0)
			(layer "B.Fab")
			(hide yes)
			(effects
				(font
					(size 1 1)
					(thickness 0.15)
				)
				(justify mirror)
			)
		)
		(property "Manufacturer" "Yaego"
			(at 326.25 194 0)
			(layer "B.Fab")
			(hide yes)
			(effects
				(font
					(size 1 1)
					(thickness 0.15)
				)
				(justify mirror)
			)
		)
		(property "Val" "100n"
			(at 326.25 194 0)
			(layer "B.Fab")
			(hide yes)
			(effects
				(font
					(size 1 1)
					(thickness 0.15)
				)
				(justify mirror)
			)
		)
		(property "Voltage" ""
			(at 326.25 194 0)
			(layer "B.Fab")
			(hide yes)
			(effects
				(font
					(size 1 1)
					(thickness 0.15)
				)
				(justify mirror)
			)
		)
		(sheetname "FPGA power")
		(sheetfile "fpga-power.kicad_sch")
		(attr smd)
		(fp_rect
			(start -0.72 0.38)
			(end 0.72 -0.38)
			(stroke
				(width 0.05)
				(type solid)
			)
			(fill no)
			(layer "B.CrtYd")
		)
		(fp_rect
			(start 0.3 -0.15)
			(end -0.301 0.149)
			(stroke
				(width 0.15)
				(type solid)
			)
			(fill no)
			(layer "B.Fab")
		)
		(pad "" smd roundrect
			(at -0.349 0.002 180)
			(size 0.318 0.36)
			(layers "B.Paste")
			(roundrect_rratio 0.25)
		)
		(pad "" smd roundrect
			(at 0.341 0.002 180)
			(size 0.318 0.36)
			(layers "B.Paste")
			(roundrect_rratio 0.25)
		)
		(pad "1" smd roundrect
			(at -0.321 0.002 180)
			(size 0.46 0.4)
			(layers "B.Cu" "B.Mask")
			(roundrect_rratio 0.25)
			(net 66 "VDDQ")
			(pintype "passive")
		)
		(pad "2" smd roundrect
			(at 0.32 0.002 180)
			(size 0.46 0.4)
			(layers "B.Cu" "B.Mask")
			(roundrect_rratio 0.25)
			(net 5 "GND")
			(pintype "passive")
		)
	)
	(footprint "antmicro-footprints:C_0201"
		(layer "B.Cu")
		(at 161 98 180)
		(descr "Capacitor SMD 0201")
		(tags "capacitor SMD 0201")
		(property "Reference" "C69"
			(at 0.5 -0.4 0)
			(layer "B.SilkS")
			(effects
				(font
					(size 0.7 0.7)
					(thickness 0.15)
				)
				(justify left bottom mirror)
			)
		)
		(property "Value" "C_100n_0201"
			(at 0 -1.4 0)
			(layer "B.Fab")
			(effects
				(font
					(size 0.7 0.7)
					(thickness 0.15)
				)
				(justify left bottom mirror)
			)
		)
		(property "Description" " "
			(at 0 0 180)
			(layer "F.Fab")
			(hide yes)
			(effects
				(font
					(size 1.27 1.27)
					(thickness 0.15)
				)
			)
		)
		(property "Author" "Antmicro"
			(at 322 196 0)
			(layer "B.Fab")
			(hide yes)
			(effects
				(font
					(size 1 1)
					(thickness 0.15)
				)
				(justify mirror)
			)
		)
		(property "Dielectric" ""
			(at 322 196 0)
			(layer "B.Fab")
			(hide yes)
			(effects
				(font
					(size 1 1)
					(thickness 0.15)
				)
				(justify mirror)
			)
		)
		(property "License" "Apache-2.0"
			(at 322 196 0)
			(layer "B.Fab")
			(hide yes)
			(effects
				(font
					(size 1 1)
					(thickness 0.15)
				)
				(justify mirror)
			)
		)
		(property "MPN" "CC0201KRX6S5BB104"
			(at 322 196 0)
			(layer "B.Fab")
			(hide yes)
			(effects
				(font
					(size 1 1)
					(thickness 0.15)
				)
				(justify mirror)
			)
		)
		(property "Manufacturer" "Yaego"
			(at 322 196 0)
			(layer "B.Fab")
			(hide yes)
			(effects
				(font
					(size 1 1)
					(thickness 0.15)
				)
				(justify mirror)
			)
		)
		(property "Val" "100n"
			(at 322 196 0)
			(layer "B.Fab")
			(hide yes)
			(effects
				(font
					(size 1 1)
					(thickness 0.15)
				)
				(justify mirror)
			)
		)
		(property "Voltage" ""
			(at 322 196 0)
			(layer "B.Fab")
			(hide yes)
			(effects
				(font
					(size 1 1)
					(thickness 0.15)
				)
				(justify mirror)
			)
		)
		(sheetname "FPGA power")
		(sheetfile "fpga-power.kicad_sch")
		(attr smd)
		(fp_rect
			(start -0.72 0.38)
			(end 0.72 -0.38)
			(stroke
				(width 0.05)
				(type solid)
			)
			(fill no)
			(layer "B.CrtYd")
		)
		(fp_rect
			(start 0.3 -0.15)
			(end -0.301 0.149)
			(stroke
				(width 0.15)
				(type solid)
			)
			(fill no)
			(layer "B.Fab")
		)
		(pad "" smd roundrect
			(at -0.349 0.002 180)
			(size 0.318 0.36)
			(layers "B.Paste")
			(roundrect_rratio 0.25)
		)
		(pad "" smd roundrect
			(at 0.341 0.002 180)
			(size 0.318 0.36)
			(layers "B.Paste")
			(roundrect_rratio 0.25)
		)
		(pad "1" smd roundrect
			(at -0.321 0.002 180)
			(size 0.46 0.4)
			(layers "B.Cu" "B.Mask")
			(roundrect_rratio 0.25)
			(net 66 "VDDQ")
			(pintype "passive")
		)
		(pad "2" smd roundrect
			(at 0.32 0.002 180)
			(size 0.46 0.4)
			(layers "B.Cu" "B.Mask")
			(roundrect_rratio 0.25)
			(net 5 "GND")
			(pintype "passive")
		)
	)
	(footprint "antmicro-footprints:C_0201"
		(layer "B.Cu")
		(at 167.5 85.875 -90)
		(descr "Capacitor SMD 0201")
		(tags "capacitor SMD 0201")
		(property "Reference" "C73"
			(at -2.675 -0.3 90)
			(layer "B.SilkS")
			(effects
				(font
					(size 0.7 0.7)
					(thickness 0.15)
				)
				(justify left bottom mirror)
			)
		)
		(property "Value" "C_100n_0201"
			(at 0 -1.4 90)
			(layer "B.Fab")
			(effects
				(font
					(size 0.7 0.7)
					(thickness 0.15)
				)
				(justify left bottom mirror)
			)
		)
		(property "Description" " "
			(at 0 0 270)
			(layer "F.Fab")
			(hide yes)
			(effects
				(font
					(size 1.27 1.27)
					(thickness 0.15)
				)
			)
		)
		(property "Author" "Antmicro"
			(at 81.625 253.375 0)
			(layer "B.Fab")
			(hide yes)
			(effects
				(font
					(size 1 1)
					(thickness 0.15)
				)
				(justify mirror)
			)
		)
		(property "Dielectric" ""
			(at 81.625 253.375 0)
			(layer "B.Fab")
			(hide yes)
			(effects
				(font
					(size 1 1)
					(thickness 0.15)
				)
				(justify mirror)
			)
		)
		(property "License" "Apache-2.0"
			(at 81.625 253.375 0)
			(layer "B.Fab")
			(hide yes)
			(effects
				(font
					(size 1 1)
					(thickness 0.15)
				)
				(justify mirror)
			)
		)
		(property "MPN" "CC0201KRX6S5BB104"
			(at 81.625 253.375 0)
			(layer "B.Fab")
			(hide yes)
			(effects
				(font
					(size 1 1)
					(thickness 0.15)
				)
				(justify mirror)
			)
		)
		(property "Manufacturer" "Yaego"
			(at 81.625 253.375 0)
			(layer "B.Fab")
			(hide yes)
			(effects
				(font
					(size 1 1)
					(thickness 0.15)
				)
				(justify mirror)
			)
		)
		(property "Val" "100n"
			(at 81.625 253.375 0)
			(layer "B.Fab")
			(hide yes)
			(effects
				(font
					(size 1 1)
					(thickness 0.15)
				)
				(justify mirror)
			)
		)
		(property "Voltage" ""
			(at 81.625 253.375 0)
			(layer "B.Fab")
			(hide yes)
			(effects
				(font
					(size 1 1)
					(thickness 0.15)
				)
				(justify mirror)
			)
		)
		(sheetname "FPGA power")
		(sheetfile "fpga-power.kicad_sch")
		(attr smd)
		(fp_rect
			(start -0.72 0.38)
			(end 0.72 -0.38)
			(stroke
				(width 0.05)
				(type solid)
			)
			(fill no)
			(layer "B.CrtYd")
		)
		(fp_rect
			(start 0.3 -0.15)
			(end -0.301 0.149)
			(stroke
				(width 0.15)
				(type solid)
			)
			(fill no)
			(layer "B.Fab")
		)
		(pad "" smd roundrect
			(at -0.349 0.002 270)
			(size 0.318 0.36)
			(layers "B.Paste")
			(roundrect_rratio 0.25)
		)
		(pad "" smd roundrect
			(at 0.341 0.002 270)
			(size 0.318 0.36)
			(layers "B.Paste")
			(roundrect_rratio 0.25)
		)
		(pad "1" smd roundrect
			(at -0.321 0.002 270)
			(size 0.46 0.4)
			(layers "B.Cu" "B.Mask")
			(roundrect_rratio 0.25)
			(net 66 "VDDQ")
			(pintype "passive")
		)
		(pad "2" smd roundrect
			(at 0.32 0.002 270)
			(size 0.46 0.4)
			(layers "B.Cu" "B.Mask")
			(roundrect_rratio 0.25)
			(net 5 "GND")
			(pintype "passive")
		)
	)
)
